# T6G (Grand Teton) — schematic netlist excerpt (pin names and nets, part order shuffled) for the footprints in the layout excerpt that follows; sources: Cadence DE-HDL packaged netlist, KiCad conversion of 04192023_DAF0TMB3IC0_F0TG_MB_C_brd_V02_OCP.brd

J102  SCONN288_DDR506112002KQ  IO  pkg DDR288S_1-1VXC  page 104
  VIN_BULK0  = P12V_MEM_CPU1
  RFU0  = NC
  VIN_MGMT  = P3V3_AUX
  HSCL  = I3C_SPD_DDRG_CPU1_SCL
  HSDA  = I3C_SPD_DDRG_CPU1_SDA
  VSS0  = GND
  DQ0_A  = M_G_CPU1_SA_DQ<0>
  VSS1  = GND
  DQ1_A  = M_G_CPU1_SA_DQ<1>
  VSS2  = GND
  DQS0_A_T  = M_G_CPU1_SA_DQS_DP<0>
  DQS0_A_C  = M_G_CPU1_SA_DQS_DN<0>
  VSS3  = GND
  DQ4_A  = M_G_CPU1_SA_DQ<4>
  VSS4  = GND
  DQ5_A  = M_G_CPU1_SA_DQ<5>
  VSS5  = GND
  DQ8_A  = M_G_CPU1_SA_DQ<8>
  VSS6  = GND
  DQ9_A  = M_G_CPU1_SA_DQ<9>
  VSS7  = GND
  DQS1_A_T  = M_G_CPU1_SA_DQS_DP<1>
  DQS1_A_C  = M_G_CPU1_SA_DQS_DN<1>
  VSS8  = GND
  DQ12_A  = M_G_CPU1_SA_DQ<12>
  VSS9  = GND
  DQ13_A  = M_G_CPU1_SA_DQ<13>
  VSS10  = GND
  DQ16_A  = M_G_CPU1_SA_DQ<16>
  VSS11  = GND
  DQ17_A  = M_G_CPU1_SA_DQ<17>
  VSS12  = GND
  DQS2_A_T  = M_G_CPU1_SA_DQS_DP<2>
  DQS2_A_C  = M_G_CPU1_SA_DQS_DN<2>
  VSS13  = GND
  DQ20_A  = M_G_CPU1_SA_DQ<20>
  VSS14  = GND
  DQ21_A  = M_G_CPU1_SA_DQ<21>
  VSS15  = GND
  DQ24_A  = M_G_CPU1_SA_DQ<24>
  VSS16  = GND
  DQ25_A  = M_G_CPU1_SA_DQ<25>
  VSS17  = GND
  DQS3_A_T  = M_G_CPU1_SA_DQS_DP<3>
  DQS3_A_C  = M_G_CPU1_SA_DQS_DN<3>
  VSS18  = GND
  DQ28_A  = M_G_CPU1_SA_DQ<28>
  VSS19  = GND
  DQ29_A  = M_G_CPU1_SA_DQ<29>
  VSS20  = GND
  CB0_A  = M_G_CPU1_SA_CB<0>
  VSS21  = GND
  CB1_A  = M_G_CPU1_SA_CB<1>
  VSS22  = GND
  DQS4_A_T  = M_G_CPU1_SA_DQS_DP<4>
  DQS4_A_C  = M_G_CPU1_SA_DQS_DN<4>
  VSS23  = GND
  CB4_A  = M_G_CPU1_SA_CB<4>
  VSS24  = GND
  CB5_A  = M_G_CPU1_SA_CB<5>
  VSS25  = GND
  ALERT_N  = M_G_CPU1_ALERT_N
  VSS26  = GND
  CS0_A_N  = M_G_CPU1_SA_CS_N<0>
  VSS27  = GND
  CA0_A  = M_G_CPU1_SA_CA<0>
  VSS28  = GND
  CA2_A  = M_G_CPU1_SA_CA<2>
  VSS29  = GND
  CA4_A  = M_G_CPU1_SA_CA<4>
  VSS30  = GND
  CA6_A  = M_G_CPU1_SA_CA<6>
  VSS31  = GND
  PAR_A  = M_G_CPU1_SA_PAR
  VSS32  = GND
  CA0_B  = M_G_CPU1_SB_CA<0>
  VSS33  = GND
  CA2_B  = M_G_CPU1_SB_CA<2>
  VSS34  = GND
  CA4_B  = M_G_CPU1_SB_CA<4>
  VSS35  = GND
  CA6_B  = M_G_CPU1_SB_CA<6>
  VSS36  = GND
  CS0_B_N  = M_G_CPU1_SB_CS_N<0>
  VSS37  = GND
  \lbd||rsp_a_n\  = M_G_CPU1_SA_RSP<0>
  \lbs||rsp_b_n\  = M_G_CPU1_SB_RSP<0>
  VSS38  = GND
  CB4_B  = M_G_CPU1_SB_CB<4>
  VSS39  = GND
  CB5_B  = M_G_CPU1_SB_CB<5>
  VSS40  = GND
  \dqs9_b_t||tdqs9_b_t||dbi4_b_n\  = M_G_CPU1_SB_DQS_DP<9>
  \dqs9_b_c||tdqs9_b_c\  = M_G_CPU1_SB_DQS_DN<9>
  VSS41  = GND
  CB0_B  = M_G_CPU1_SB_CB<0>
  VSS42  = GND
  CB1_B  = M_G_CPU1_SB_CB<1>
  VSS43  = GND
  DQ0_B  = M_G_CPU1_SB_DQ<0>
  VSS44  = GND
  DQ1_B  = M_G_CPU1_SB_DQ<1>
  VSS45  = GND
  DQS0_B_T  = M_G_CPU1_SB_DQS_DP<0>
  DQS0_B_C  = M_G_CPU1_SB_DQS_DN<0>
  VSS46  = GND
  DQ4_B  = M_G_CPU1_SB_DQ<4>
  VSS47  = GND
  DQ5_B  = M_G_CPU1_SB_DQ<5>
  VSS48  = GND
  DQ8_B  = M_G_CPU1_SB_DQ<8>
  VSS49  = GND
  DQ9_B  = M_G_CPU1_SB_DQ<9>
  VSS50  = GND
  DQS1_B_T  = M_G_CPU1_SB_DQS_DP<1>
  DQS1_B_C  = M_G_CPU1_SB_DQS_DN<1>
  VSS51  = GND
  DQ12_B  = M_G_CPU1_SB_DQ<12>
  VSS52  = GND
  DQ13_B  = M_G_CPU1_SB_DQ<13>
  VSS53  = GND
  DQ16_B  = M_G_CPU1_SB_DQ<16>
  VSS54  = GND
  DQ17_B  = M_G_CPU1_SB_DQ<17>
  VSS55  = GND
  DQS2_B_T  = M_G_CPU1_SB_DQS_DP<2>
  DQS2_B_C  = M_G_CPU1_SB_DQS_DN<2>
  VSS56  = GND
  DQ20_B  = M_G_CPU1_SB_DQ<20>
  VSS57  = GND
  DQ21_B  = M_G_CPU1_SB_DQ<21>
  VSS58  = GND
  DQ24_B  = M_G_CPU1_SB_DQ<24>
  VSS59  = GND
  DQ25_B  = M_G_CPU1_SB_DQ<25>
  VSS60  = GND
  DQS3_B_T  = M_G_CPU1_SB_DQS_DP<3>
  DQS3_B_C  = M_G_CPU1_SB_DQS_DN<3>
  VSS61  = GND
  DQ28_B  = M_G_CPU1_SB_DQ<28>
  VSS62  = GND
  DQ29_B  = M_G_CPU1_SB_DQ<29>
  VSS63  = GND
  RFU1  = NC
  VIN_BULK1  = P12V_MEM_CPU1
  VIN_BULK2  = P12V_MEM_CPU1
  \pwr_good||fail_n\  = PWRGD_CHG_CPU1_DIMM0
  HAS  = PD_CHG_CPU1_DIMM0_SAA
  RFU2  = NC
  RFU3  = NC
  VSS64  = GND
  DQ2_A  = M_G_CPU1_SA_DQ<2>
  VSS65  = GND
  DQ3_A  = M_G_CPU1_SA_DQ<3>
  VSS66  = GND
  \dqs5_a_c||tdqs5_a_c||dqs5_a_t||tdqs5_a_t\  = M_G_CPU1_SA_DQS_DN<5>
  \dqs5_a_t||tdqs5_a_t\  = M_G_CPU1_SA_DQS_DP<5>
  VSS67  = GND
  DQ6_A  = M_G_CPU1_SA_DQ<6>
  VSS68  = GND
  DQ7_A  = M_G_CPU1_SA_DQ<7>
  VSS69  = GND
  DQ10_A  = M_G_CPU1_SA_DQ<10>
  VSS70  = GND
  DQ11_A  = M_G_CPU1_SA_DQ<11>
  VSS71  = GND
  \dqs6_a_c||tdqs6_a_c||dqs6_a_t||tdqs6_a_t\  = M_G_CPU1_SA_DQS_DN<6>
  \dqs6_a_t||tdqs6_a_t\  = M_G_CPU1_SA_DQS_DP<6>
  VSS72  = GND
  DQ14_A  = M_G_CPU1_SA_DQ<14>
  VSS73  = GND
  DQ15_A  = M_G_CPU1_SA_DQ<15>
  VSS74  = GND
  DQ18_A  = M_G_CPU1_SA_DQ<18>
  VSS75  = GND
  DQ19_A  = M_G_CPU1_SA_DQ<19>
  VSS76  = GND
  \dqs7_a_c||tdqs7_a_c\  = M_G_CPU1_SA_DQS_DN<7>
  \dqs7_a_t||tdqs7_a_t\  = M_G_CPU1_SA_DQS_DP<7>
  VSS77  = GND
  DQ22_A  = M_G_CPU1_SA_DQ<22>
  VSS78  = GND
  DQ23_A  = M_G_CPU1_SA_DQ<23>
  VSS79  = GND
  DQ26_A  = M_G_CPU1_SA_DQ<26>
  VSS80  = GND
  DQ27_A  = M_G_CPU1_SA_DQ<27>
  VSS81  = GND
  \dqs8_a_c||tdqs8_a_c\  = M_G_CPU1_SA_DQS_DN<8>
  \dqs8_a_t||tdqs8_a_t\  = M_G_CPU1_SA_DQS_DP<8>
  VSS82  = GND
  DQ30_A  = M_G_CPU1_SA_DQ<30>
  VSS83  = GND
  DQ31_A  = M_G_CPU1_SA_DQ<31>
  VSS84  = GND
  CB2_A  = M_G_CPU1_SA_CB<2>
  VSS85  = GND
  CB3_A  = M_G_CPU1_SA_CB<3>
  VSS86  = GND
  \dqs9_a_c||tdqs9_a_c\  = M_G_CPU1_SA_DQS_DN<9>
  \dqs9_a_t||tdqs9_a_t\  = M_G_CPU1_SA_DQS_DP<9>
  VSS87  = GND
  CB6_A  = M_G_CPU1_SA_CB<6>
  VSS88  = GND
  CB7_A  = M_G_CPU1_SA_CB<7>
  VSS89  = GND
  RESET_N  = M_G_CPU1_RESET_N
  VSS90  = GND
  CS1_A_N  = M_G_CPU1_SA_CS_N<1>
  VSS91  = GND
  CA1_A  = M_G_CPU1_SA_CA<1>
  VSS92  = GND
  CA3_A  = M_G_CPU1_SA_CA<3>
  VSS93  = GND
  CA5_A  = M_G_CPU1_SA_CA<5>
  VSS94  = GND
  CK_T  = M_G_CPU1_CLK_DP<0>
  CK_C  = M_G_CPU1_CLK_DN<0>
  VSS95  = GND
  RFU4  = NC
  CA1_B  = M_G_CPU1_SB_CA<1>
  VSS96  = GND
  CA3_B  = M_G_CPU1_SB_CA<3>
  VSS97  = GND
  CA5_B  = M_G_CPU1_SB_CA<5>
  VSS98  = GND
  PAR_B  = M_G_CPU1_SB_PAR
  VSS99  = GND
  CS1_B_N  = M_G_CPU1_SB_CS_N<1>
  VSS100  = GND
  RFU5  = NC
  RFU6  = NC
  VSS101  = GND
  CB6_B  = M_G_CPU1_SB_CB<6>
  VSS102  = GND
  CB7_B  = M_G_CPU1_SB_CB<7>
  VSS103  = GND
  DQS4_B_C  = M_G_CPU1_SB_DQS_DN<4>
  DQS4_B_T  = M_G_CPU1_SB_DQS_DP<4>
  VSS104  = GND
  CB2_B  = M_G_CPU1_SB_CB<2>
  VSS105  = GND
  CB3_B  = M_G_CPU1_SB_CB<3>
  VSS106  = GND
  DQ2_B  = M_G_CPU1_SB_DQ<2>
  VSS107  = GND
  DQ3_B  = M_G_CPU1_SB_DQ<3>
  VSS108  = GND
  \dqs5_b_c||tdqs5_b_c\  = M_G_CPU1_SB_DQS_DN<5>
  \dqs5_b_t||tdqs5_b_t\  = M_G_CPU1_SB_DQS_DP<5>
  VSS109  = GND
  DQ6_B  = M_G_CPU1_SB_DQ<6>
  VSS110  = GND
  DQ7_B  = M_G_CPU1_SB_DQ<7>
  VSS111  = GND
  DQ10_B  = M_G_CPU1_SB_DQ<10>
  VSS112  = GND
  DQ11_B  = M_G_CPU1_SB_DQ<11>
  VSS113  = GND
  \dqs6_b_c||tdqs6_b_c\  = M_G_CPU1_SB_DQS_DN<6>
  \dqs6_b_t||tdqs6_b_t\  = M_G_CPU1_SB_DQS_DP<6>
  VSS114  = GND
  DQ14_B  = M_G_CPU1_SB_DQ<14>
  VSS115  = GND
  DQ15_B  = M_G_CPU1_SB_DQ<15>
  VSS116  = GND
  DQ18_B  = M_G_CPU1_SB_DQ<18>
  VSS117  = GND
  DQ19_B  = M_G_CPU1_SB_DQ<19>
  VSS118  = GND
  \dqs7_b_c||tdqs7_b_c\  = M_G_CPU1_SB_DQS_DN<7>
  \dqs7_b_t||tdqs7_b_t\  = M_G_CPU1_SB_DQS_DP<7>
  VSS119  = GND
  DQ22_B  = M_G_CPU1_SB_DQ<22>
  VSS120  = GND
  DQ23_B  = M_G_CPU1_SB_DQ<23>
  VSS121  = GND
  DQ26_B  = M_G_CPU1_SB_DQ<26>
  VSS122  = GND
  DQ27_B  = M_G_CPU1_SB_DQ<27>
  VSS123  = GND
  \dqs8_b_c||tdqs8_b_c\  = M_G_CPU1_SB_DQS_DN<8>
  \dqs8_b_t||tdqs8_b_t\  = M_G_CPU1_SB_DQS_DP<8>
  VSS124  = GND
  DQ30_B  = M_G_CPU1_SB_DQ<30>
  VSS125  = GND
  DQ31_B  = M_G_CPU1_SB_DQ<31>
  VSS126  = GND
  G1  = GND
  G2  = GND
  G3  = GND

(kicad_pcb
	(version 20260206)
	(generator "pcbnew")
	(generator_version "10.0")
	(general
		(thickness 1.6)
		(legacy_teardrops no)
	)
	(paper "A4")
	(title_block
		(title "04192023_DAF0TMB3IC0_F0TG_MB_C_brd_V02_OCP.brd")
		(comment 1 "Grand Teton / footprint 4934 of 8354 (J102), pads 93-138 of 291")
	)
	(layers
		(0 "F.Cu" signal "TOP")
		(4 "In1.Cu" signal "GND")
		(6 "In2.Cu" signal "IN1")
		(8 "In3.Cu" signal "GND1")
		(10 "In4.Cu" signal "IN2")
		(12 "In5.Cu" signal "GND2")
		(14 "In6.Cu" signal "IN3")
		(16 "In7.Cu" signal "GND3")
		(18 "In8.Cu" signal "VCC")
		(20 "In9.Cu" signal "VCC1")
		(22 "In10.Cu" signal "GND4")
		(24 "In11.Cu" signal "IN4")
		(26 "In12.Cu" signal "GND5")
		(28 "In13.Cu" signal "IN5")
		(30 "In14.Cu" signal "GND6")
		(32 "In15.Cu" signal "IN6")
		(34 "In16.Cu" signal "GND7")
		(2 "B.Cu" signal "BOTTOM")
		(9 "F.Adhes" user "F.Adhesive")
		(11 "B.Adhes" user "B.Adhesive")
		(13 "F.Paste" user "Package Geometry/Pastemask Top")
		(15 "B.Paste" user "Package Geometry/Pastemask Bottom")
		(5 "F.SilkS" user "Ref Des/Silkscreen Top")
		(7 "B.SilkS" user "Ref Des/Silkscreen Bottom")
		(1 "F.Mask" user "Board Geometry/Soldermask Top")
		(3 "B.Mask" user "Board Geometry/Soldermask Bottom")
		(17 "Dwgs.User" user "User.Drawings")
		(19 "Cmts.User" user "User.Comments")
		(21 "Eco1.User" user "User.Eco1")
		(23 "Eco2.User" user "User.Eco2")
		(25 "Edge.Cuts" user "Board Geometry/Outline")
		(27 "Margin" user)
		(31 "F.CrtYd" user "Package Geometry/Place Bound Top")
		(29 "B.CrtYd" user "Package Geometry/Place Bound Bottom")
		(35 "F.Fab" user "Ref Des/Assembly Top")
		(33 "B.Fab" user "Ref Des/Assembly Bottom")
	)
	(footprint ""
		(layer "F.Cu")
		(at 166.47795 -255.560322 180)
		(property "Reference" "J102"
			(at -2.7178 -81.857088 0)
			(unlocked yes)
			(layer "F.SilkS")
			(effects
				(font
					(size 0.7874 0.5842)
					(thickness 0.1524)
				)
			)
		)
		(property "Value" ""
			(at 0 0 180)
			(layer "F.Fab")
			(effects
				(font
					(size 1.27 1.27)
				)
			)
		)
		(duplicate_pad_numbers_are_jumpers no)
		(pad "93" smd rect
			(at -2.050034 19.975068 90)
			(size 0.519938 1.4986)
			(layers "F.Cu" "F.Mask" "F.Paste")
			(net "M_G_CPU1_SB_DQS_DP<9>")
		)
		(pad "94" smd rect
			(at -2.050034 20.824952 90)
			(size 0.519938 1.4986)
			(layers "F.Cu" "F.Mask" "F.Paste")
			(net "M_G_CPU1_SB_DQS_DN<9>")
		)
		(pad "95" smd rect
			(at -2.050034 21.67509 90)
			(size 0.519938 1.4986)
			(layers "F.Cu" "F.Mask" "F.Paste")
			(net "GND")
		)
		(pad "96" smd rect
			(at -2.050034 22.524974 90)
			(size 0.519938 1.4986)
			(layers "F.Cu" "F.Mask" "F.Paste")
			(net "M_G_CPU1_SB_CB<0>")
		)
		(pad "97" smd rect
			(at -2.050034 23.375112 90)
			(size 0.519938 1.4986)
			(layers "F.Cu" "F.Mask" "F.Paste")
			(net "GND")
		)
		(pad "98" smd rect
			(at -2.050034 24.224996 90)
			(size 0.519938 1.4986)
			(layers "F.Cu" "F.Mask" "F.Paste")
			(net "M_G_CPU1_SB_CB<1>")
		)
		(pad "99" smd rect
			(at -2.050034 25.07488 90)
			(size 0.519938 1.4986)
			(layers "F.Cu" "F.Mask" "F.Paste")
			(net "GND")
		)
		(pad "100" smd rect
			(at -2.050034 25.925018 90)
			(size 0.519938 1.4986)
			(layers "F.Cu" "F.Mask" "F.Paste")
			(net "M_G_CPU1_SB_DQ<0>")
		)
		(pad "101" smd rect
			(at -2.050034 26.774902 90)
			(size 0.519938 1.4986)
			(layers "F.Cu" "F.Mask" "F.Paste")
			(net "GND")
		)
		(pad "102" smd rect
			(at -2.050034 27.62504 90)
			(size 0.519938 1.4986)
			(layers "F.Cu" "F.Mask" "F.Paste")
			(net "M_G_CPU1_SB_DQ<1>")
		)
		(pad "103" smd rect
			(at -2.050034 28.474924 90)
			(size 0.519938 1.4986)
			(layers "F.Cu" "F.Mask" "F.Paste")
			(net "GND")
		)
		(pad "104" smd rect
			(at -2.050034 29.325062 90)
			(size 0.519938 1.4986)
			(layers "F.Cu" "F.Mask" "F.Paste")
			(net "M_G_CPU1_SB_DQS_DP<0>")
		)
		(pad "105" smd rect
			(at -2.050034 30.174946 90)
			(size 0.519938 1.4986)
			(layers "F.Cu" "F.Mask" "F.Paste")
			(net "M_G_CPU1_SB_DQS_DN<0>")
		)
		(pad "106" smd rect
			(at -2.050034 31.025084 90)
			(size 0.519938 1.4986)
			(layers "F.Cu" "F.Mask" "F.Paste")
			(net "GND")
		)
		(pad "107" smd rect
			(at -2.050034 31.874968 90)
			(size 0.519938 1.4986)
			(layers "F.Cu" "F.Mask" "F.Paste")
			(net "M_G_CPU1_SB_DQ<4>")
		)
		(pad "108" smd rect
			(at -2.050034 32.725106 90)
			(size 0.519938 1.4986)
			(layers "F.Cu" "F.Mask" "F.Paste")
			(net "GND")
		)
		(pad "109" smd rect
			(at -2.050034 33.57499 90)
			(size 0.519938 1.4986)
			(layers "F.Cu" "F.Mask" "F.Paste")
			(net "M_G_CPU1_SB_DQ<5>")
		)
		(pad "110" smd rect
			(at -2.050034 34.425128 90)
			(size 0.519938 1.4986)
			(layers "F.Cu" "F.Mask" "F.Paste")
			(net "GND")
		)
		(pad "111" smd rect
			(at -2.050034 35.275012 90)
			(size 0.519938 1.4986)
			(layers "F.Cu" "F.Mask" "F.Paste")
			(net "M_G_CPU1_SB_DQ<8>")
		)
		(pad "112" smd rect
			(at -2.050034 36.124896 90)
			(size 0.519938 1.4986)
			(layers "F.Cu" "F.Mask" "F.Paste")
			(net "GND")
		)
		(pad "113" smd rect
			(at -2.050034 36.975034 90)
			(size 0.519938 1.4986)
			(layers "F.Cu" "F.Mask" "F.Paste")
			(net "M_G_CPU1_SB_DQ<9>")
		)
		(pad "114" smd rect
			(at -2.050034 37.824918 90)
			(size 0.519938 1.4986)
			(layers "F.Cu" "F.Mask" "F.Paste")
			(net "GND")
		)
		(pad "115" smd rect
			(at -2.050034 38.675056 90)
			(size 0.519938 1.4986)
			(layers "F.Cu" "F.Mask" "F.Paste")
			(net "M_G_CPU1_SB_DQS_DP<1>")
		)
		(pad "116" smd rect
			(at -2.050034 39.52494 90)
			(size 0.519938 1.4986)
			(layers "F.Cu" "F.Mask" "F.Paste")
			(net "M_G_CPU1_SB_DQS_DN<1>")
		)
		(pad "117" smd rect
			(at -2.050034 40.375078 90)
			(size 0.519938 1.4986)
			(layers "F.Cu" "F.Mask" "F.Paste")
			(net "GND")
		)
		(pad "118" smd rect
			(at -2.050034 41.224962 90)
			(size 0.519938 1.4986)
			(layers "F.Cu" "F.Mask" "F.Paste")
			(net "M_G_CPU1_SB_DQ<12>")
		)
		(pad "119" smd rect
			(at -2.050034 42.0751 90)
			(size 0.519938 1.4986)
			(layers "F.Cu" "F.Mask" "F.Paste")
			(net "GND")
		)
		(pad "120" smd rect
			(at -2.050034 42.924984 90)
			(size 0.519938 1.4986)
			(layers "F.Cu" "F.Mask" "F.Paste")
			(net "M_G_CPU1_SB_DQ<13>")
		)
		(pad "121" smd rect
			(at -2.050034 43.775122 90)
			(size 0.519938 1.4986)
			(layers "F.Cu" "F.Mask" "F.Paste")
			(net "GND")
		)
		(pad "122" smd rect
			(at -2.050034 44.625006 90)
			(size 0.519938 1.4986)
			(layers "F.Cu" "F.Mask" "F.Paste")
			(net "M_G_CPU1_SB_DQ<16>")
		)
		(pad "123" smd rect
			(at -2.050034 45.47489 90)
			(size 0.519938 1.4986)
			(layers "F.Cu" "F.Mask" "F.Paste")
			(net "GND")
		)
		(pad "124" smd rect
			(at -2.050034 46.325028 90)
			(size 0.519938 1.4986)
			(layers "F.Cu" "F.Mask" "F.Paste")
			(net "M_G_CPU1_SB_DQ<17>")
		)
		(pad "125" smd rect
			(at -2.050034 47.174912 90)
			(size 0.519938 1.4986)
			(layers "F.Cu" "F.Mask" "F.Paste")
			(net "GND")
		)
		(pad "126" smd rect
			(at -2.050034 48.02505 90)
			(size 0.519938 1.4986)
			(layers "F.Cu" "F.Mask" "F.Paste")
			(net "M_G_CPU1_SB_DQS_DP<2>")
		)
		(pad "127" smd rect
			(at -2.050034 48.874934 90)
			(size 0.519938 1.4986)
			(layers "F.Cu" "F.Mask" "F.Paste")
			(net "M_G_CPU1_SB_DQS_DN<2>")
		)
		(pad "128" smd rect
			(at -2.050034 49.725072 90)
			(size 0.519938 1.4986)
			(layers "F.Cu" "F.Mask" "F.Paste")
			(net "GND")
		)
		(pad "129" smd rect
			(at -2.050034 50.574956 90)
			(size 0.519938 1.4986)
			(layers "F.Cu" "F.Mask" "F.Paste")
			(net "M_G_CPU1_SB_DQ<20>")
		)
		(pad "130" smd rect
			(at -2.050034 51.425094 90)
			(size 0.519938 1.4986)
			(layers "F.Cu" "F.Mask" "F.Paste")
			(net "GND")
		)
		(pad "131" smd rect
			(at -2.050034 52.274978 90)
			(size 0.519938 1.4986)
			(layers "F.Cu" "F.Mask" "F.Paste")
			(net "M_G_CPU1_SB_DQ<21>")
		)
		(pad "132" smd rect
			(at -2.050034 53.125116 90)
			(size 0.519938 1.4986)
			(layers "F.Cu" "F.Mask" "F.Paste")
			(net "GND")
		)
		(pad "133" smd rect
			(at -2.050034 53.975 90)
			(size 0.519938 1.4986)
			(layers "F.Cu" "F.Mask" "F.Paste")
			(net "M_G_CPU1_SB_DQ<24>")
		)
		(pad "134" smd rect
			(at -2.050034 54.824884 90)
			(size 0.519938 1.4986)
			(layers "F.Cu" "F.Mask" "F.Paste")
			(net "GND")
		)
		(pad "135" smd rect
			(at -2.050034 55.675022 90)
			(size 0.519938 1.4986)
			(layers "F.Cu" "F.Mask" "F.Paste")
			(net "M_G_CPU1_SB_DQ<25>")
		)
		(pad "136" smd rect
			(at -2.050034 56.524906 90)
			(size 0.519938 1.4986)
			(layers "F.Cu" "F.Mask" "F.Paste")
			(net "GND")
		)
		(pad "137" smd rect
			(at -2.050034 57.375044 90)
			(size 0.519938 1.4986)
			(layers "F.Cu" "F.Mask" "F.Paste")
			(net "M_G_CPU1_SB_DQS_DP<3>")
		)
		(pad "138" smd rect
			(at -2.050034 58.224928 90)
			(size 0.519938 1.4986)
			(layers "F.Cu" "F.Mask" "F.Paste")
			(net "M_G_CPU1_SB_DQS_DN<3>")
		)
	)
)
